# T6G (Grand Teton) — schematic netlist excerpt (pin names and nets, part order shuffled) for the footprints in the layout excerpt that follows; sources: Cadence DE-HDL packaged netlist, KiCad conversion of 04192023_DAF0TMB3IC0_F0TG_MB_C_brd_V02_OCP.brd

Q28  MOSFET_DUAL_6P  2N7002KDW IC  pkg SOT363XD  page 85
  S1  = GND
  G1  = BMC_FPGA_LED1
  D2  = BMC_FPGA_LED2_N
  S2  = GND
  G2  = BMC_FPGA_LED2
  D1  = BMC_FPGA_LED1_N

C6569  Q_CAP_DIFFBUS  DIFF BUS_0.22UF 6.3V 20% X6S  pkg C0201  page 297 : \1\ = P5E_CPU0_P2_TX_BUF_C_DP<2> ; \2\ = P5E_CPU0_P2_TX_BUF_DP<2>

(kicad_pcb
	(version 20260206)
	(generator "pcbnew")
	(generator_version "10.0")
	(general
		(thickness 1.6)
		(legacy_teardrops no)
	)
	(paper "A4")
	(title_block
		(title "04192023_DAF0TMB3IC0_F0TG_MB_C_brd_V02_OCP.brd")
		(comment 1 "Grand Teton / footprints 4639-4640 of 8354")
	)
	(layers
		(0 "F.Cu" signal "TOP")
		(4 "In1.Cu" signal "GND")
		(6 "In2.Cu" signal "IN1")
		(8 "In3.Cu" signal "GND1")
		(10 "In4.Cu" signal "IN2")
		(12 "In5.Cu" signal "GND2")
		(14 "In6.Cu" signal "IN3")
		(16 "In7.Cu" signal "GND3")
		(18 "In8.Cu" signal "VCC")
		(20 "In9.Cu" signal "VCC1")
		(22 "In10.Cu" signal "GND4")
		(24 "In11.Cu" signal "IN4")
		(26 "In12.Cu" signal "GND5")
		(28 "In13.Cu" signal "IN5")
		(30 "In14.Cu" signal "GND6")
		(32 "In15.Cu" signal "IN6")
		(34 "In16.Cu" signal "GND7")
		(2 "B.Cu" signal "BOTTOM")
		(9 "F.Adhes" user "F.Adhesive")
		(11 "B.Adhes" user "B.Adhesive")
		(13 "F.Paste" user "Package Geometry/Pastemask Top")
		(15 "B.Paste" user "Package Geometry/Pastemask Bottom")
		(5 "F.SilkS" user "Ref Des/Silkscreen Top")
		(7 "B.SilkS" user "Ref Des/Silkscreen Bottom")
		(1 "F.Mask" user "Board Geometry/Soldermask Top")
		(3 "B.Mask" user "Board Geometry/Soldermask Bottom")
		(17 "Dwgs.User" user "User.Drawings")
		(19 "Cmts.User" user "User.Comments")
		(21 "Eco1.User" user "User.Eco1")
		(23 "Eco2.User" user "User.Eco2")
		(25 "Edge.Cuts" user "Board Geometry/Outline")
		(27 "Margin" user)
		(31 "F.CrtYd" user "Package Geometry/Place Bound Top")
		(29 "B.CrtYd" user "Package Geometry/Place Bound Bottom")
		(35 "F.Fab" user "Ref Des/Assembly Top")
		(33 "B.Fab" user "Ref Des/Assembly Bottom")
	)
	(footprint ""
		(layer "F.Cu")
		(at 331.58303 -20.397978)
		(property "Reference" "Q28"
			(at -3.251962 1.45542 90)
			(unlocked yes)
			(layer "F.SilkS")
			(effects
				(font
					(size 0.7874 0.5842)
					(thickness 0.1524)
				)
				(justify left)
			)
		)
		(property "Value" ""
			(at 0 0 0)
			(layer "F.Fab")
			(effects
				(font
					(size 1.27 1.27)
				)
			)
		)
		(duplicate_pad_numbers_are_jumpers no)
		(fp_line
			(start -1.332738 -1.100074)
			(end -0.4826 -1.100074)
			(stroke
				(width 0.1524)
				(type default)
			)
			(layer "F.SilkS")
		)
		(fp_line
			(start -1.332738 1.100074)
			(end -1.332738 -1.100074)
			(stroke
				(width 0.1524)
				(type default)
			)
			(layer "F.SilkS")
		)
		(fp_line
			(start -0.4826 -1.100074)
			(end 0 -0.541274)
			(stroke
				(width 0.1524)
				(type default)
			)
			(layer "F.SilkS")
		)
		(fp_line
			(start 0 -0.541274)
			(end 0.4826 -1.100074)
			(stroke
				(width 0.1524)
				(type default)
			)
			(layer "F.SilkS")
		)
		(fp_line
			(start 0.4826 -1.100074)
			(end 1.332738 -1.100074)
			(stroke
				(width 0.1524)
				(type default)
			)
			(layer "F.SilkS")
		)
		(fp_line
			(start 1.332738 -1.100074)
			(end 1.332738 1.100074)
			(stroke
				(width 0.1524)
				(type default)
			)
			(layer "F.SilkS")
		)
		(fp_line
			(start 1.332738 1.100074)
			(end -1.332738 1.100074)
			(stroke
				(width 0.1524)
				(type default)
			)
			(layer "F.SilkS")
		)
		(fp_poly
			(pts
				(xy -1.533144 -0.649986) (xy -2.2352 -0.298958) (xy -2.2352 -1.001014)
			)
			(stroke
				(width 0)
				(type default)
			)
			(fill yes)
			(layer "F.SilkS")
		)
		(fp_line
			(start -0.674878 -1.100074)
			(end 0.674878 -1.100074)
			(stroke
				(width 0.1)
				(type default)
			)
			(layer "F.Fab")
		)
		(fp_line
			(start -0.674878 1.100074)
			(end -0.674878 -1.100074)
			(stroke
				(width 0.1)
				(type default)
			)
			(layer "F.Fab")
		)
		(fp_line
			(start 0.674878 -1.100074)
			(end 0.674878 1.100074)
			(stroke
				(width 0.1)
				(type default)
			)
			(layer "F.Fab")
		)
		(fp_line
			(start 0.674878 1.100074)
			(end -0.674878 1.100074)
			(stroke
				(width 0.1)
				(type default)
			)
			(layer "F.Fab")
		)
		(fp_poly
			(pts
				(xy -2.2352 -0.298958) (xy -2.2352 -1.001014) (xy -1.533144 -0.649986)
			)
			(stroke
				(width 0)
				(type default)
			)
			(fill yes)
			(layer "F.Fab")
		)
		(pad "1" smd rect
			(at -0.94996 -0.649986 90)
			(size 0.4318 0.508)
			(layers "F.Cu" "F.Mask" "F.Paste")
			(net "GND")
		)
		(pad "2" smd rect
			(at -0.94996 0 90)
			(size 0.4318 0.508)
			(layers "F.Cu" "F.Mask" "F.Paste")
			(net "BMC_FPGA_LED1")
		)
		(pad "3" smd rect
			(at -0.94996 0.649986 90)
			(size 0.4318 0.508)
			(layers "F.Cu" "F.Mask" "F.Paste")
			(net "BMC_FPGA_LED2_N")
		)
		(pad "4" smd rect
			(at 0.94996 0.649986 90)
			(size 0.4318 0.508)
			(layers "F.Cu" "F.Mask" "F.Paste")
			(net "GND")
		)
		(pad "5" smd rect
			(at 0.94996 0 90)
			(size 0.4318 0.508)
			(layers "F.Cu" "F.Mask" "F.Paste")
			(net "BMC_FPGA_LED2")
		)
		(pad "6" smd rect
			(at 0.94996 -0.649986 90)
			(size 0.4318 0.508)
			(layers "F.Cu" "F.Mask" "F.Paste")
			(net "BMC_FPGA_LED1_N")
		)
	)
	(footprint ""
		(layer "F.Cu")
		(at 377.909582 -416.899344 -90)
		(property "Reference" "C6569"
			(at 0 0 270)
			(layer "F.SilkS")
			(hide yes)
			(effects
				(font
					(size 1.27 1.27)
				)
			)
		)
		(property "Value" ""
			(at 0 0 270)
			(layer "F.Fab")
			(effects
				(font
					(size 1.27 1.27)
				)
			)
		)
		(duplicate_pad_numbers_are_jumpers no)
		(fp_line
			(start -0.299974 0.150114)
			(end -0.299974 -0.150114)
			(stroke
				(width 0.1)
				(type default)
			)
			(layer "F.Fab")
		)
		(fp_line
			(start 0.299974 0.150114)
			(end -0.299974 0.150114)
			(stroke
				(width 0.1)
				(type default)
			)
			(layer "F.Fab")
		)
		(fp_line
			(start -0.299974 -0.150114)
			(end 0.299974 -0.150114)
			(stroke
				(width 0.1)
				(type default)
			)
			(layer "F.Fab")
		)
		(fp_line
			(start 0.299974 -0.150114)
			(end 0.299974 0.150114)
			(stroke
				(width 0.1)
				(type default)
			)
			(layer "F.Fab")
		)
		(pad "1" smd rect
			(at -0.2667 0 270)
			(size 0.3048 0.381)
			(layers "F.Cu" "F.Mask" "F.Paste")
			(net "P5E_CPU0_P2_TX_BUF_C_DP<2>")
		)
		(pad "2" smd rect
			(at 0.2667 0 270)
			(size 0.3048 0.381)
			(layers "F.Cu" "F.Mask" "F.Paste")
			(net "P5E_CPU0_P2_TX_BUF_DP<2>")
		)
	)
)
